# BASEBOARD_FAB2 (Tioga Pass) — schematic netlist excerpt (pin names and nets, part order shuffled) for the footprints in the layout excerpt that follows; sources: Cadence DE-HDL packaged netlist, KiCad conversion of Wiwynn_Tioga_Pass_MB.brd

R7D41  RES  0.0 5% CHIP  pkg 0402  page 93 : A = FM_CPU1_PROCHOT_LVT3_R_N ; B = FM_CPU1_PROCHOT_LVT3_K_N
C3T15  CAPP  68UF 16V 20% TANT  pkg 3018  page 195 : A = P12V_STBY ; B = GND
C9L12  CAPP  470UF 2.5V 20% ALUM  pkg 3018  page 228 : A = PVDDQ_KLM ; B = GND

(kicad_pcb
	(version 20260206)
	(generator "pcbnew")
	(generator_version "10.0")
	(general
		(thickness 1.6)
		(legacy_teardrops no)
	)
	(paper "A4")
	(title_block
		(title "Wiwynn_Tioga_Pass_MB.brd")
		(comment 1 "Tioga Pass / footprints 4448-4450 of 4770")
	)
	(layers
		(0 "F.Cu" signal "TOP")
		(4 "In1.Cu" signal "L2GND")
		(6 "In2.Cu" signal "L3")
		(8 "In3.Cu" signal "L4GND")
		(10 "In4.Cu" signal "L5")
		(12 "In5.Cu" signal "L6GND")
		(14 "In6.Cu" signal "L7VCC")
		(16 "In7.Cu" signal "L8VCC")
		(18 "In8.Cu" signal "L9GND")
		(20 "In9.Cu" signal "L10")
		(22 "In10.Cu" signal "L11GND")
		(24 "In11.Cu" signal "L12")
		(26 "In12.Cu" signal "L13GND")
		(2 "B.Cu" signal "BOTTOM")
		(9 "F.Adhes" user "F.Adhesive")
		(11 "B.Adhes" user "B.Adhesive")
		(13 "F.Paste" user "Package Geometry/Pastemask Top")
		(15 "B.Paste" user "Package Geometry/Pastemask Bottom")
		(5 "F.SilkS" user "Ref Des/Silkscreen Top")
		(7 "B.SilkS" user "Ref Des/Silkscreen Bottom")
		(1 "F.Mask" user "Board Geometry/Soldermask Top")
		(3 "B.Mask" user "Board Geometry/Soldermask Bottom")
		(17 "Dwgs.User" user "User.Drawings")
		(19 "Cmts.User" user "User.Comments")
		(21 "Eco1.User" user "User.Eco1")
		(23 "Eco2.User" user "User.Eco2")
		(25 "Edge.Cuts" user "Board Geometry/Outline")
		(27 "Margin" user)
		(31 "F.CrtYd" user "Package Geometry/Place Bound Top")
		(29 "B.CrtYd" user "Package Geometry/Place Bound Bottom")
		(35 "F.Fab" user "Ref Des/Assembly Top")
		(33 "B.Fab" user "Ref Des/Assembly Bottom")
	)
	(footprint ""
		(layer "B.Cu")
		(at 362.270294 -46.433486 180)
		(property "Reference" "R7D41"
			(at 0 0 0)
			(layer "B.SilkS")
			(hide yes)
			(effects
				(font
					(size 1.27 1.27)
				)
				(justify mirror)
			)
		)
		(property "Value" ""
			(at 0 0 0)
			(layer "B.Fab")
			(effects
				(font
					(size 1.27 1.27)
				)
				(justify mirror)
			)
		)
		(duplicate_pad_numbers_are_jumpers no)
		(fp_poly
			(pts
				(xy 0.2794 -0.1016) (xy -0.2794 -0.1016) (xy -0.2794 0.9906) (xy 0.2794 0.9906)
			)
			(stroke
				(width 0)
				(type default)
			)
			(fill no)
			(layer "B.CrtYd")
		)
		(fp_line
			(start 0.2794 0.9906)
			(end -0.2794 0.9906)
			(stroke
				(width 0.1)
				(type default)
			)
			(layer "B.Fab")
		)
		(fp_line
			(start 0.2794 -0.1016)
			(end 0.2794 0.9906)
			(stroke
				(width 0.1)
				(type default)
			)
			(layer "B.Fab")
		)
		(fp_line
			(start -0.2794 0.9906)
			(end -0.2794 -0.1016)
			(stroke
				(width 0.1)
				(type default)
			)
			(layer "B.Fab")
		)
		(fp_line
			(start -0.2794 -0.1016)
			(end 0.2794 -0.1016)
			(stroke
				(width 0.1)
				(type default)
			)
			(layer "B.Fab")
		)
		(pad "1" smd rect
			(at 0 0)
			(size 0.508 0.508)
			(layers "B.Cu" "B.Mask" "B.Paste")
			(net "FM_CPU1_PROCHOT_LVT3_R_N")
		)
		(pad "2" smd rect
			(at 0 0.889)
			(size 0.508 0.508)
			(layers "B.Cu" "B.Mask" "B.Paste")
			(net "FM_CPU1_PROCHOT_LVT3_K_N")
		)
		(zone
			(layer "B.Cu")
			(hatch none 0.5)
			(connect_pads
				(clearance 0)
			)
			(min_thickness 0.25)
			(keepout
				(tracks not_allowed)
				(vias allowed)
				(pads allowed)
				(copperpour not_allowed)
				(footprints allowed)
			)
			(placement
				(enabled no)
				(sheetname "")
			)
			(fill
				(thermal_gap 0.5)
				(thermal_bridge_width 0.5)
				(island_removal_mode 0)
			)
			(polygon
				(pts
					(xy 362.016294 -47.068486) (xy 362.524294 -47.068486) (xy 362.524294 -46.687486) (xy 362.016294 -46.687486)
				)
			)
		)
		(zone
			(layer "B.Cu")
			(hatch none 0.5)
			(connect_pads
				(clearance 0)
			)
			(min_thickness 0.25)
			(keepout
				(tracks allowed)
				(vias not_allowed)
				(pads allowed)
				(copperpour not_allowed)
				(footprints allowed)
			)
			(placement
				(enabled no)
				(sheetname "")
			)
			(fill
				(thermal_gap 0.5)
				(thermal_bridge_width 0.5)
				(island_removal_mode 0)
			)
			(polygon
				(pts
					(xy 362.016294 -46.687486) (xy 362.524294 -46.687486) (xy 362.524294 -47.068486) (xy 362.016294 -47.068486)
				)
			)
		)
	)
	(footprint ""
		(layer "B.Cu")
		(at 361.188 -23.241)
		(property "Reference" "C3T15"
			(at -3.20167 3.81 270)
			(unlocked yes)
			(layer "B.SilkS")
			(effects
				(font
					(size 0.7874 0.5842)
					(thickness 0.1524)
				)
				(justify mirror)
			)
		)
		(property "Value" ""
			(at 0 0 0)
			(layer "B.Fab")
			(effects
				(font
					(size 1.27 1.27)
				)
				(justify mirror)
			)
		)
		(duplicate_pad_numbers_are_jumpers no)
		(fp_line
			(start -2.504948 -1.616456)
			(end -2.504948 1.633728)
			(stroke
				(width 0.1524)
				(type default)
			)
			(layer "B.SilkS")
		)
		(fp_line
			(start -2.504948 1.633728)
			(end -1.6002 1.633728)
			(stroke
				(width 0.1524)
				(type default)
			)
			(layer "B.SilkS")
		)
		(fp_line
			(start -2.286 7.366)
			(end -2.286 1.63195)
			(stroke
				(width 0.1524)
				(type default)
			)
			(layer "B.SilkS")
		)
		(fp_line
			(start -2.286 7.366)
			(end -1.600708 7.366)
			(stroke
				(width 0.1524)
				(type default)
			)
			(layer "B.SilkS")
		)
		(fp_line
			(start -1.6002 -1.616456)
			(end -2.504948 -1.616456)
			(stroke
				(width 0.1524)
				(type default)
			)
			(layer "B.SilkS")
		)
		(fp_line
			(start 1.6002 -1.616456)
			(end 2.563114 -1.616456)
			(stroke
				(width 0.1524)
				(type default)
			)
			(layer "B.SilkS")
		)
		(fp_line
			(start 2.286 7.366)
			(end 1.60147 7.366)
			(stroke
				(width 0.1524)
				(type default)
			)
			(layer "B.SilkS")
		)
		(fp_line
			(start 2.286 7.366)
			(end 2.286 1.632712)
			(stroke
				(width 0.1524)
				(type default)
			)
			(layer "B.SilkS")
		)
		(fp_line
			(start 2.563114 -1.616456)
			(end 2.563114 1.633728)
			(stroke
				(width 0.1524)
				(type default)
			)
			(layer "B.SilkS")
		)
		(fp_line
			(start 2.563114 1.633728)
			(end 1.6002 1.633728)
			(stroke
				(width 0.1524)
				(type default)
			)
			(layer "B.SilkS")
		)
		(fp_rect
			(start 2.286 7.366)
			(end -2.286 -0.254)
			(stroke
				(width 0)
				(type default)
			)
			(fill no)
			(layer "B.CrtYd")
		)
		(fp_line
			(start -2.286 -0.254)
			(end -2.286 7.366)
			(stroke
				(width 0.1)
				(type default)
			)
			(layer "B.Fab")
		)
		(fp_line
			(start -2.286 7.366)
			(end 2.286 7.366)
			(stroke
				(width 0.1)
				(type default)
			)
			(layer "B.Fab")
		)
		(fp_line
			(start 2.286 -0.254)
			(end -2.286 -0.254)
			(stroke
				(width 0.1)
				(type default)
			)
			(layer "B.Fab")
		)
		(fp_line
			(start 2.286 7.366)
			(end 2.286 -0.254)
			(stroke
				(width 0.1)
				(type default)
			)
			(layer "B.Fab")
		)
		(pad "1" smd rect
			(at 0 0 180)
			(size 2.54 3.048)
			(layers "B.Cu" "B.Mask" "B.Paste")
			(net "P12V_STBY")
		)
		(pad "2" smd rect
			(at 0 7.112 180)
			(size 2.54 3.048)
			(layers "B.Cu" "B.Mask" "B.Paste")
			(net "GND")
		)
	)
	(footprint ""
		(layer "B.Cu")
		(at 18.0086 -139.1666 -90)
		(property "Reference" "C9L12"
			(at -2.03073 9.6266 0)
			(unlocked yes)
			(layer "B.SilkS")
			(effects
				(font
					(size 0.7874 0.5842)
					(thickness 0.1524)
				)
				(justify mirror)
			)
		)
		(property "Value" ""
			(at 0 0 90)
			(layer "B.Fab")
			(effects
				(font
					(size 1.27 1.27)
				)
				(justify mirror)
			)
		)
		(duplicate_pad_numbers_are_jumpers no)
		(fp_line
			(start -2.286 7.366)
			(end -1.600708 7.366)
			(stroke
				(width 0.1524)
				(type default)
			)
			(layer "B.SilkS")
		)
		(fp_line
			(start -2.286 7.366)
			(end -2.286 1.63195)
			(stroke
				(width 0.1524)
				(type default)
			)
			(layer "B.SilkS")
		)
		(fp_line
			(start 2.286 7.366)
			(end 1.60147 7.366)
			(stroke
				(width 0.1524)
				(type default)
			)
			(layer "B.SilkS")
		)
		(fp_line
			(start 2.286 7.366)
			(end 2.286 1.632712)
			(stroke
				(width 0.1524)
				(type default)
			)
			(layer "B.SilkS")
		)
		(fp_line
			(start -2.504948 1.633728)
			(end -1.6002 1.633728)
			(stroke
				(width 0.1524)
				(type default)
			)
			(layer "B.SilkS")
		)
		(fp_line
			(start 2.563114 1.633728)
			(end 1.6002 1.633728)
			(stroke
				(width 0.1524)
				(type default)
			)
			(layer "B.SilkS")
		)
		(fp_line
			(start -2.504948 -1.616456)
			(end -2.504948 1.633728)
			(stroke
				(width 0.1524)
				(type default)
			)
			(layer "B.SilkS")
		)
		(fp_line
			(start -1.6002 -1.616456)
			(end -2.504948 -1.616456)
			(stroke
				(width 0.1524)
				(type default)
			)
			(layer "B.SilkS")
		)
		(fp_line
			(start 1.6002 -1.616456)
			(end 2.563114 -1.616456)
			(stroke
				(width 0.1524)
				(type default)
			)
			(layer "B.SilkS")
		)
		(fp_line
			(start 2.563114 -1.616456)
			(end 2.563114 1.633728)
			(stroke
				(width 0.1524)
				(type default)
			)
			(layer "B.SilkS")
		)
		(fp_rect
			(start 2.286 -0.254)
			(end -2.286 7.366)
			(stroke
				(width 0)
				(type default)
			)
			(fill no)
			(layer "B.CrtYd")
		)
		(fp_line
			(start -2.286 7.366)
			(end 2.286 7.366)
			(stroke
				(width 0.1)
				(type default)
			)
			(layer "B.Fab")
		)
		(fp_line
			(start 2.286 7.366)
			(end 2.286 -0.254)
			(stroke
				(width 0.1)
				(type default)
			)
			(layer "B.Fab")
		)
		(fp_line
			(start -2.286 -0.254)
			(end -2.286 7.366)
			(stroke
				(width 0.1)
				(type default)
			)
			(layer "B.Fab")
		)
		(fp_line
			(start 2.286 -0.254)
			(end -2.286 -0.254)
			(stroke
				(width 0.1)
				(type default)
			)
			(layer "B.Fab")
		)
		(pad "1" smd rect
			(at 0 0 90)
			(size 2.54 3.048)
			(layers "B.Cu" "B.Mask" "B.Paste")
			(net "PVDDQ_KLM")
		)
		(pad "2" smd rect
			(at 0 7.112 90)
			(size 2.54 3.048)
			(layers "B.Cu" "B.Mask" "B.Paste")
			(net "GND")
		)
	)
)
